(kicad_pcb
	(version 20260206)
	(generator "pcbnew")
	(generator_version "10.0")
	(general
		(thickness 1.6)
		(legacy_teardrops no)
	)
	(paper "A4")
	(title_block
		(title "v1-chassis-manager — T6M_CM_d_v01_1031_1645.brd")
		(comment 1 "Open CloudServer (Microsoft) / footprints 1855-1864 of 2512")
	)
	(layers
		(0 "F.Cu" signal "TOP")
		(4 "In1.Cu" signal "GND1")
		(6 "In2.Cu" signal "IN1")
		(8 "In3.Cu" signal "VCC1")
		(10 "In4.Cu" signal "VCC2")
		(12 "In5.Cu" signal "GND2")
		(14 "In6.Cu" signal "IN2")
		(16 "In7.Cu" signal "IN3")
		(18 "In8.Cu" signal "GND3")
		(2 "B.Cu" signal "BOTTOM")
		(9 "F.Adhes" user "F.Adhesive")
		(11 "B.Adhes" user "B.Adhesive")
		(13 "F.Paste" user "Package Geometry/Pastemask Top")
		(15 "B.Paste" user "Package Geometry/Pastemask Bottom")
		(5 "F.SilkS" user "Ref Des/Silkscreen Top")
		(7 "B.SilkS" user "Ref Des/Silkscreen Bottom")
		(1 "F.Mask" user "Board Geometry/Soldermask Top")
		(3 "B.Mask" user "Board Geometry/Soldermask Bottom")
		(17 "Dwgs.User" user "User.Drawings")
		(19 "Cmts.User" user "User.Comments")
		(21 "Eco1.User" user "User.Eco1")
		(23 "Eco2.User" user "User.Eco2")
		(25 "Edge.Cuts" user "Board Geometry/Outline")
		(27 "Margin" user)
		(31 "F.CrtYd" user "Package Geometry/Place Bound Top")
		(29 "B.CrtYd" user "Package Geometry/Place Bound Bottom")
		(35 "F.Fab" user "Ref Des/Assembly Top")
		(33 "B.Fab" user "Ref Des/Assembly Bottom")
	)
	(footprint ""
		(layer "B.Cu")
		(at 123.70816 -177.458624)
		(property "Reference" "R724"
			(at -28.598876 31.521146 0)
			(unlocked yes)
			(layer "B.SilkS")
			(effects
				(font
					(size 0.7874 0.5842)
					(thickness 0.1524)
				)
				(justify left mirror)
			)
		)
		(property "Value" ""
			(at 0 0 0)
			(layer "B.Fab")
			(effects
				(font
					(size 1.27 1.27)
				)
				(justify mirror)
			)
		)
		(duplicate_pad_numbers_are_jumpers no)
		(fp_line
			(start -0.7874 -0.4064)
			(end -0.7874 0.4064)
			(stroke
				(width 0.1524)
				(type default)
			)
			(layer "B.SilkS")
		)
		(fp_line
			(start -0.7874 0.4064)
			(end 0.7874 0.4064)
			(stroke
				(width 0.1524)
				(type default)
			)
			(layer "B.SilkS")
		)
		(fp_line
			(start 0.7874 -0.4064)
			(end -0.7874 -0.4064)
			(stroke
				(width 0.1524)
				(type default)
			)
			(layer "B.SilkS")
		)
		(fp_line
			(start 0.7874 0.4064)
			(end 0.7874 -0.4064)
			(stroke
				(width 0.1524)
				(type default)
			)
			(layer "B.SilkS")
		)
		(fp_poly
			(pts
				(xy 0.508 0.2794) (xy 0.508 0.2286) (xy 0.635 0.2286) (xy 0.635 -0.254) (xy 0.5334 -0.254) (xy 0.5334 -0.2794)
				(xy -0.5334 -0.2794) (xy -0.5334 -0.254) (xy -0.635 -0.254) (xy -0.635 0.254) (xy -0.5334 0.254)
				(xy -0.5334 0.2794)
			)
			(stroke
				(width 0)
				(type default)
			)
			(fill no)
			(layer "B.CrtYd")
		)
		(pad "1" smd rect
			(at -0.40005 0 180)
			(size 0.4572 0.508)
			(layers "B.Cu" "B.Mask" "B.Paste")
			(net "T8_NODE1_EN")
		)
		(pad "2" smd rect
			(at 0.40005 0 180)
			(size 0.4572 0.508)
			(layers "B.Cu" "B.Mask" "B.Paste")
			(net "P5V_NODE1")
		)
	)
	(footprint ""
		(layer "B.Cu")
		(at 66.53276 -188.126624 -90)
		(property "Reference" "C622"
			(at -4.318254 0.375666 270)
			(unlocked yes)
			(layer "B.SilkS")
			(effects
				(font
					(size 0.7874 0.5842)
					(thickness 0.1524)
				)
				(justify left mirror)
			)
		)
		(property "Value" ""
			(at 0 0 90)
			(layer "B.Fab")
			(effects
				(font
					(size 1.27 1.27)
				)
				(justify mirror)
			)
		)
		(duplicate_pad_numbers_are_jumpers no)
		(fp_line
			(start -0.7874 0.4064)
			(end 0.7874 0.4064)
			(stroke
				(width 0.1524)
				(type default)
			)
			(layer "B.SilkS")
		)
		(fp_line
			(start 0.7874 0.4064)
			(end 0.7874 -0.4064)
			(stroke
				(width 0.1524)
				(type default)
			)
			(layer "B.SilkS")
		)
		(fp_line
			(start 0 0.381)
			(end 0 -0.381)
			(stroke
				(width 0.1524)
				(type default)
			)
			(layer "B.SilkS")
		)
		(fp_line
			(start -0.7874 -0.4064)
			(end -0.7874 0.4064)
			(stroke
				(width 0.1524)
				(type default)
			)
			(layer "B.SilkS")
		)
		(fp_line
			(start 0.7874 -0.4064)
			(end -0.7874 -0.4064)
			(stroke
				(width 0.1524)
				(type default)
			)
			(layer "B.SilkS")
		)
		(fp_poly
			(pts
				(xy 0.5334 0.254) (xy 0.635 0.254) (xy 0.635 0.2286) (xy 0.635 -0.254) (xy 0.5334 -0.254) (xy 0.5334 -0.2794)
				(xy -0.5334 -0.2794) (xy -0.5334 -0.254) (xy -0.635 -0.254) (xy -0.635 0.254) (xy -0.5334 0.254)
				(xy -0.5334 0.2794) (xy 0.508 0.2794) (xy 0.5334 0.2794)
			)
			(stroke
				(width 0)
				(type default)
			)
			(fill no)
			(layer "B.CrtYd")
		)
		(pad "1" smd rect
			(at -0.40005 0 90)
			(size 0.4572 0.508)
			(layers "B.Cu" "B.Mask" "B.Paste")
			(net "T1_NODE1_EN_R")
		)
		(pad "2" smd rect
			(at 0.40005 0 90)
			(size 0.4572 0.508)
			(layers "B.Cu" "B.Mask" "B.Paste")
			(net "GND")
		)
	)
	(footprint ""
		(layer "B.Cu")
		(at 114.15776 -188.126624 90)
		(property "Reference" "R961"
			(at 4.080256 0.757682 270)
			(unlocked yes)
			(layer "B.SilkS")
			(effects
				(font
					(size 0.7874 0.5842)
					(thickness 0.1524)
				)
				(justify left mirror)
			)
		)
		(property "Value" ""
			(at 0 0 90)
			(layer "B.Fab")
			(effects
				(font
					(size 1.27 1.27)
				)
				(justify mirror)
			)
		)
		(duplicate_pad_numbers_are_jumpers no)
		(fp_line
			(start 0.7874 -0.4064)
			(end -0.7874 -0.4064)
			(stroke
				(width 0.1524)
				(type default)
			)
			(layer "B.SilkS")
		)
		(fp_line
			(start -0.7874 -0.4064)
			(end -0.7874 0.4064)
			(stroke
				(width 0.1524)
				(type default)
			)
			(layer "B.SilkS")
		)
		(fp_line
			(start 0.7874 0.4064)
			(end 0.7874 -0.4064)
			(stroke
				(width 0.1524)
				(type default)
			)
			(layer "B.SilkS")
		)
		(fp_line
			(start -0.7874 0.4064)
			(end 0.7874 0.4064)
			(stroke
				(width 0.1524)
				(type default)
			)
			(layer "B.SilkS")
		)
		(fp_poly
			(pts
				(xy 0.508 0.2794) (xy 0.508 0.2286) (xy 0.635 0.2286) (xy 0.635 -0.254) (xy 0.5334 -0.254) (xy 0.5334 -0.2794)
				(xy -0.5334 -0.2794) (xy -0.5334 -0.254) (xy -0.635 -0.254) (xy -0.635 0.254) (xy -0.5334 0.254)
				(xy -0.5334 0.2794)
			)
			(stroke
				(width 0)
				(type default)
			)
			(fill no)
			(layer "B.CrtYd")
		)
		(pad "1" smd rect
			(at -0.40005 0 270)
			(size 0.4572 0.508)
			(layers "B.Cu" "B.Mask" "B.Paste")
			(net "UART_T7_NODE2_RXD")
		)
		(pad "2" smd rect
			(at 0.40005 0 270)
			(size 0.4572 0.508)
			(layers "B.Cu" "B.Mask" "B.Paste")
			(net "UART_T7_NODE2_RXD_R")
		)
	)
	(footprint ""
		(layer "B.Cu")
		(at 142.07236 -169.965624)
		(property "Reference" "R743"
			(at -1.237234 0.53086 0)
			(unlocked yes)
			(layer "B.SilkS")
			(effects
				(font
					(size 0.7874 0.5842)
					(thickness 0.1524)
				)
				(justify left mirror)
			)
		)
		(property "Value" ""
			(at 0 0 0)
			(layer "B.Fab")
			(effects
				(font
					(size 1.27 1.27)
				)
				(justify mirror)
			)
		)
		(duplicate_pad_numbers_are_jumpers no)
		(fp_line
			(start -0.7874 -0.4064)
			(end -0.7874 0.4064)
			(stroke
				(width 0.1524)
				(type default)
			)
			(layer "B.SilkS")
		)
		(fp_line
			(start -0.7874 0.4064)
			(end 0.7874 0.4064)
			(stroke
				(width 0.1524)
				(type default)
			)
			(layer "B.SilkS")
		)
		(fp_line
			(start 0.7874 -0.4064)
			(end -0.7874 -0.4064)
			(stroke
				(width 0.1524)
				(type default)
			)
			(layer "B.SilkS")
		)
		(fp_line
			(start 0.7874 0.4064)
			(end 0.7874 -0.4064)
			(stroke
				(width 0.1524)
				(type default)
			)
			(layer "B.SilkS")
		)
		(fp_poly
			(pts
				(xy 0.508 0.2794) (xy 0.508 0.2286) (xy 0.635 0.2286) (xy 0.635 -0.254) (xy 0.5334 -0.254) (xy 0.5334 -0.2794)
				(xy -0.5334 -0.2794) (xy -0.5334 -0.254) (xy -0.635 -0.254) (xy -0.635 0.254) (xy -0.5334 0.254)
				(xy -0.5334 0.2794)
			)
			(stroke
				(width 0)
				(type default)
			)
			(fill no)
			(layer "B.CrtYd")
		)
		(pad "1" smd rect
			(at -0.40005 0 180)
			(size 0.4572 0.508)
			(layers "B.Cu" "B.Mask" "B.Paste")
			(net "P3V3_NODE1")
		)
		(pad "2" smd rect
			(at 0.40005 0 180)
			(size 0.4572 0.508)
			(layers "B.Cu" "B.Mask" "B.Paste")
			(net "N21698757")
		)
	)
	(footprint ""
		(layer "B.Cu")
		(at 61.884306 -61.525912)
		(property "Reference" "R35"
			(at -0.221234 2.098802 0)
			(unlocked yes)
			(layer "B.SilkS")
			(effects
				(font
					(size 0.7874 0.5842)
					(thickness 0.1524)
				)
				(justify left mirror)
			)
		)
		(property "Value" ""
			(at 0 0 0)
			(layer "B.Fab")
			(effects
				(font
					(size 1.27 1.27)
				)
				(justify mirror)
			)
		)
		(duplicate_pad_numbers_are_jumpers no)
		(fp_line
			(start -0.7874 -0.4064)
			(end -0.7874 0.4064)
			(stroke
				(width 0.1524)
				(type default)
			)
			(layer "B.SilkS")
		)
		(fp_line
			(start -0.7874 0.4064)
			(end 0.7874 0.4064)
			(stroke
				(width 0.1524)
				(type default)
			)
			(layer "B.SilkS")
		)
		(fp_line
			(start 0.7874 -0.4064)
			(end -0.7874 -0.4064)
			(stroke
				(width 0.1524)
				(type default)
			)
			(layer "B.SilkS")
		)
		(fp_line
			(start 0.7874 0.4064)
			(end 0.7874 -0.4064)
			(stroke
				(width 0.1524)
				(type default)
			)
			(layer "B.SilkS")
		)
		(fp_poly
			(pts
				(xy 0.508 0.2794) (xy 0.508 0.2286) (xy 0.635 0.2286) (xy 0.635 -0.254) (xy 0.5334 -0.254) (xy 0.5334 -0.2794)
				(xy -0.5334 -0.2794) (xy -0.5334 -0.254) (xy -0.635 -0.254) (xy -0.635 0.254) (xy -0.5334 0.254)
				(xy -0.5334 0.2794)
			)
			(stroke
				(width 0)
				(type default)
			)
			(fill no)
			(layer "B.CrtYd")
		)
		(pad "1" smd rect
			(at -0.40005 0 180)
			(size 0.4572 0.508)
			(layers "B.Cu" "B.Mask" "B.Paste")
			(net "M_DDR3_NODE1_MON2P")
		)
		(pad "2" smd rect
			(at 0.40005 0 180)
			(size 0.4572 0.508)
			(layers "B.Cu" "B.Mask" "B.Paste")
			(net "M_DDR3_NODE1_MON2N")
		)
	)
	(footprint ""
		(layer "B.Cu")
		(at 55.044086 -123.152662 90)
		(property "Reference" "C295"
			(at -55.125874 -42.18559 270)
			(unlocked yes)
			(layer "B.SilkS")
			(effects
				(font
					(size 0.7874 0.5842)
					(thickness 0.1524)
				)
				(justify left mirror)
			)
		)
		(property "Value" ""
			(at 0 0 90)
			(layer "B.Fab")
			(effects
				(font
					(size 1.27 1.27)
				)
				(justify mirror)
			)
		)
		(duplicate_pad_numbers_are_jumpers no)
		(fp_line
			(start 0.7874 -0.4064)
			(end -0.7874 -0.4064)
			(stroke
				(width 0.1524)
				(type default)
			)
			(layer "B.SilkS")
		)
		(fp_line
			(start -0.7874 -0.4064)
			(end -0.7874 0.4064)
			(stroke
				(width 0.1524)
				(type default)
			)
			(layer "B.SilkS")
		)
		(fp_line
			(start 0 0.381)
			(end 0 -0.381)
			(stroke
				(width 0.1524)
				(type default)
			)
			(layer "B.SilkS")
		)
		(fp_line
			(start 0.7874 0.4064)
			(end 0.7874 -0.4064)
			(stroke
				(width 0.1524)
				(type default)
			)
			(layer "B.SilkS")
		)
		(fp_line
			(start -0.7874 0.4064)
			(end 0.7874 0.4064)
			(stroke
				(width 0.1524)
				(type default)
			)
			(layer "B.SilkS")
		)
		(fp_poly
			(pts
				(xy 0.5334 0.254) (xy 0.635 0.254) (xy 0.635 0.2286) (xy 0.635 -0.254) (xy 0.5334 -0.254) (xy 0.5334 -0.2794)
				(xy -0.5334 -0.2794) (xy -0.5334 -0.254) (xy -0.635 -0.254) (xy -0.635 0.254) (xy -0.5334 0.254)
				(xy -0.5334 0.2794) (xy 0.508 0.2794) (xy 0.5334 0.2794)
			)
			(stroke
				(width 0)
				(type default)
			)
			(fill no)
			(layer "B.CrtYd")
		)
		(pad "1" smd rect
			(at -0.40005 0 270)
			(size 0.4572 0.508)
			(layers "B.Cu" "B.Mask" "B.Paste")
			(net "BMC_NODE1_V1PLLAV12")
		)
		(pad "2" smd rect
			(at 0.40005 0 270)
			(size 0.4572 0.508)
			(layers "B.Cu" "B.Mask" "B.Paste")
			(net "GND")
		)
	)
	(footprint ""
		(layer "B.Cu")
		(at 56.24576 -185.205624 90)
		(property "Reference" "R928"
			(at 4.15163 0.203962 270)
			(unlocked yes)
			(layer "B.SilkS")
			(effects
				(font
					(size 0.7874 0.5842)
					(thickness 0.1524)
				)
				(justify left mirror)
			)
		)
		(property "Value" ""
			(at 0 0 90)
			(layer "B.Fab")
			(effects
				(font
					(size 1.27 1.27)
				)
				(justify mirror)
			)
		)
		(duplicate_pad_numbers_are_jumpers no)
		(fp_line
			(start 0.7874 -0.4064)
			(end -0.7874 -0.4064)
			(stroke
				(width 0.1524)
				(type default)
			)
			(layer "B.SilkS")
		)
		(fp_line
			(start -0.7874 -0.4064)
			(end -0.7874 0.4064)
			(stroke
				(width 0.1524)
				(type default)
			)
			(layer "B.SilkS")
		)
		(fp_line
			(start 0.7874 0.4064)
			(end 0.7874 -0.4064)
			(stroke
				(width 0.1524)
				(type default)
			)
			(layer "B.SilkS")
		)
		(fp_line
			(start -0.7874 0.4064)
			(end 0.7874 0.4064)
			(stroke
				(width 0.1524)
				(type default)
			)
			(layer "B.SilkS")
		)
		(fp_poly
			(pts
				(xy 0.508 0.2794) (xy 0.508 0.2286) (xy 0.635 0.2286) (xy 0.635 -0.254) (xy 0.5334 -0.254) (xy 0.5334 -0.2794)
				(xy -0.5334 -0.2794) (xy -0.5334 -0.254) (xy -0.635 -0.254) (xy -0.635 0.254) (xy -0.5334 0.254)
				(xy -0.5334 0.2794)
			)
			(stroke
				(width 0)
				(type default)
			)
			(fill no)
			(layer "B.CrtYd")
		)
		(pad "1" smd rect
			(at -0.40005 0 270)
			(size 0.4572 0.508)
			(layers "B.Cu" "B.Mask" "B.Paste")
			(net "UART_T1_NODE4_TXD")
		)
		(pad "2" smd rect
			(at 0.40005 0 270)
			(size 0.4572 0.508)
			(layers "B.Cu" "B.Mask" "B.Paste")
			(net "UART_T1_NODE4_TXD_R")
		)
	)
	(footprint ""
		(layer "B.Cu")
		(at 90.81262 -165.894512)
		(property "Reference" "R786"
			(at 24.774144 20.136104 0)
			(unlocked yes)
			(layer "B.SilkS")
			(effects
				(font
					(size 0.7874 0.5842)
					(thickness 0.1524)
				)
				(justify left mirror)
			)
		)
		(property "Value" ""
			(at 0 0 0)
			(layer "B.Fab")
			(effects
				(font
					(size 1.27 1.27)
				)
				(justify mirror)
			)
		)
		(duplicate_pad_numbers_are_jumpers no)
		(fp_line
			(start -0.7874 -0.4064)
			(end -0.7874 0.4064)
			(stroke
				(width 0.1524)
				(type default)
			)
			(layer "B.SilkS")
		)
		(fp_line
			(start -0.7874 0.4064)
			(end 0.7874 0.4064)
			(stroke
				(width 0.1524)
				(type default)
			)
			(layer "B.SilkS")
		)
		(fp_line
			(start 0.7874 -0.4064)
			(end -0.7874 -0.4064)
			(stroke
				(width 0.1524)
				(type default)
			)
			(layer "B.SilkS")
		)
		(fp_line
			(start 0.7874 0.4064)
			(end 0.7874 -0.4064)
			(stroke
				(width 0.1524)
				(type default)
			)
			(layer "B.SilkS")
		)
		(fp_poly
			(pts
				(xy 0.508 0.2794) (xy 0.508 0.2286) (xy 0.635 0.2286) (xy 0.635 -0.254) (xy 0.5334 -0.254) (xy 0.5334 -0.2794)
				(xy -0.5334 -0.2794) (xy -0.5334 -0.254) (xy -0.635 -0.254) (xy -0.635 0.254) (xy -0.5334 0.254)
				(xy -0.5334 0.2794)
			)
			(stroke
				(width 0)
				(type default)
			)
			(fill no)
			(layer "B.CrtYd")
		)
		(pad "1" smd rect
			(at -0.40005 0 180)
			(size 0.4572 0.508)
			(layers "B.Cu" "B.Mask" "B.Paste")
			(net "UART_SW_S2_N")
		)
		(pad "2" smd rect
			(at 0.40005 0 180)
			(size 0.4572 0.508)
			(layers "B.Cu" "B.Mask" "B.Paste")
			(net "P3V3_NODE1")
		)
	)
	(footprint ""
		(layer "B.Cu")
		(at 132.4356 -46.9646 90)
		(property "Reference" "R1324"
			(at 3.048 11.42873 270)
			(unlocked yes)
			(layer "B.SilkS")
			(effects
				(font
					(size 0.7874 0.5842)
					(thickness 0.1524)
				)
				(justify left mirror)
			)
		)
		(property "Value" ""
			(at 0 0 90)
			(layer "B.Fab")
			(effects
				(font
					(size 1.27 1.27)
				)
				(justify mirror)
			)
		)
		(duplicate_pad_numbers_are_jumpers no)
		(fp_line
			(start 0.7874 -0.4064)
			(end -0.7874 -0.4064)
			(stroke
				(width 0.1524)
				(type default)
			)
			(layer "B.SilkS")
		)
		(fp_line
			(start -0.7874 -0.4064)
			(end -0.7874 0.4064)
			(stroke
				(width 0.1524)
				(type default)
			)
			(layer "B.SilkS")
		)
		(fp_line
			(start 0.7874 0.4064)
			(end 0.7874 -0.4064)
			(stroke
				(width 0.1524)
				(type default)
			)
			(layer "B.SilkS")
		)
		(fp_line
			(start -0.7874 0.4064)
			(end 0.7874 0.4064)
			(stroke
				(width 0.1524)
				(type default)
			)
			(layer "B.SilkS")
		)
		(fp_poly
			(pts
				(xy 0.508 0.2794) (xy 0.508 0.2286) (xy 0.635 0.2286) (xy 0.635 -0.254) (xy 0.5334 -0.254) (xy 0.5334 -0.2794)
				(xy -0.5334 -0.2794) (xy -0.5334 -0.254) (xy -0.635 -0.254) (xy -0.635 0.254) (xy -0.5334 0.254)
				(xy -0.5334 0.2794)
			)
			(stroke
				(width 0)
				(type default)
			)
			(fill no)
			(layer "B.CrtYd")
		)
		(pad "1" smd rect
			(at -0.40005 0 270)
			(size 0.4572 0.508)
			(layers "B.Cu" "B.Mask" "B.Paste")
			(net "UART_RI_P4_N")
		)
		(pad "2" smd rect
			(at 0.40005 0 270)
			(size 0.4572 0.508)
			(layers "B.Cu" "B.Mask" "B.Paste")
			(net "UART_RI_P4_R_N")
		)
	)
	(footprint ""
		(layer "B.Cu")
		(at 81.784698 -136.557258 -90)
		(property "Reference" "R1098"
			(at -1.358138 0.544322 270)
			(unlocked yes)
			(layer "B.SilkS")
			(effects
				(font
					(size 0.7874 0.5842)
					(thickness 0.1524)
				)
				(justify left mirror)
			)
		)
		(property "Value" ""
			(at 0 0 90)
			(layer "B.Fab")
			(effects
				(font
					(size 1.27 1.27)
				)
				(justify mirror)
			)
		)
		(duplicate_pad_numbers_are_jumpers no)
		(fp_line
			(start -0.7874 0.4064)
			(end 0.7874 0.4064)
			(stroke
				(width 0.1524)
				(type default)
			)
			(layer "B.SilkS")
		)
		(fp_line
			(start 0.7874 0.4064)
			(end 0.7874 -0.4064)
			(stroke
				(width 0.1524)
				(type default)
			)
			(layer "B.SilkS")
		)
		(fp_line
			(start -0.7874 -0.4064)
			(end -0.7874 0.4064)
			(stroke
				(width 0.1524)
				(type default)
			)
			(layer "B.SilkS")
		)
		(fp_line
			(start 0.7874 -0.4064)
			(end -0.7874 -0.4064)
			(stroke
				(width 0.1524)
				(type default)
			)
			(layer "B.SilkS")
		)
		(fp_poly
			(pts
				(xy 0.508 0.2794) (xy 0.508 0.2286) (xy 0.635 0.2286) (xy 0.635 -0.254) (xy 0.5334 -0.254) (xy 0.5334 -0.2794)
				(xy -0.5334 -0.2794) (xy -0.5334 -0.254) (xy -0.635 -0.254) (xy -0.635 0.254) (xy -0.5334 0.254)
				(xy -0.5334 0.2794)
			)
			(stroke
				(width 0)
				(type default)
			)
			(fill no)
			(layer "B.CrtYd")
		)
		(pad "1" smd rect
			(at -0.40005 0 90)
			(size 0.4572 0.508)
			(layers "B.Cu" "B.Mask" "B.Paste")
			(net "P1V26_BMC_NODE1_ADJ")
		)
		(pad "2" smd rect
			(at 0.40005 0 90)
			(size 0.4572 0.508)
			(layers "B.Cu" "B.Mask" "B.Paste")
			(net "GND")
		)
	)
)
